G04 ================== begin FILE IDENTIFICATION RECORD ==================*
G04 Layout Name:  DAT6MTH3AD0_t6m_cm_d_brd_103112_274.brd*
G04 Film Name:    outline*
G04 File Format:  Gerber RS274X*
G04 File Origin:  Cadence Allegro 16.3-S048*
G04 Origin Date:  Tue Nov 26 10:18:25 2013*
G04 *
G04 Layer:  BOARD GEOMETRY/OUTLINE*
G04 *
G04 Offset:    (0.00 0.00)*
G04 Mirror:    No*
G04 Mode:      Positive*
G04 Rotation:  0*
G04 FullContactRelief:  No*
G04 UndefLineWidth:     6.00*
G04 ================== end FILE IDENTIFICATION RECORD ====================*
%FSLAX25Y25*MOIN*%
%IR0*IPPOS*OFA0.00000B0.00000*MIA0B0*SFA1.00000B1.00000*%
%ADD10C,.006*%
G75*
%LPD*%
G75*
G54D10*
G01X-42372Y125213D02*
G02I-2500J0D01*
G01X-44872Y127713D02*
G03Y122713I0J-2500D01*
G03Y127713I0J2500D01*
G01X-42372Y125213D02*
G03X-47372I-2500J0D01*
G03X-42372I2500J0D01*
G01X-44872Y127713D02*
G03I0J-2500D01*
G01X-42372Y141213D02*
G02I-2500J0D01*
G01X-44872Y143713D02*
G03Y138713I0J-2500D01*
G03Y143713I0J2500D01*
G01X-42372Y141213D02*
G03X-47372I-2500J0D01*
G03X-42372I2500J0D01*
G01X-44872Y143713D02*
G03I0J-2500D01*
G01X-42372Y232533D02*
G02I-2500J0D01*
G01X-44872Y235033D02*
G03Y230033I0J-2500D01*
G03Y235033I0J2500D01*
G01D02*
G03Y230033I0J-2500D01*
G03Y235033I0J2500D01*
G01X-42372Y232533D02*
G03X-47372I-2500J0D01*
G03X-42372I2500J0D01*
G01X-44872Y235033D02*
G03I0J-2500D01*
G01D02*
G02I0J-2500D01*
G01X-42372Y248533D02*
G02I-2500J0D01*
G01X-44872Y251033D02*
G03Y246033I0J-2500D01*
G03Y251033I0J2500D01*
G01D02*
G03Y246033I0J-2500D01*
G03Y251033I0J2500D01*
G01X-42372Y248533D02*
G03X-47372I-2500J0D01*
G03X-42372I2500J0D01*
G01X-44872Y251033D02*
G03I0J-2500D01*
G01D02*
G02I0J-2500D01*
G01X-42372Y738493D02*
G02I-2500J0D01*
G01X-44872Y735993D02*
G03Y740993I0J2500D01*
G03Y735993I0J-2500D01*
G01X-42372Y738493D02*
G03X-47372I-2500J0D01*
G03X-42372I2500J0D01*
G01X-44872Y735993D02*
G03I0J2500D01*
G01X-42372Y754493D02*
G02I-2500J0D01*
G01X-44872Y751993D02*
G03Y756993I0J2500D01*
G03Y751993I0J-2500D01*
G01X-42372Y754493D02*
G03X-47372I-2500J0D01*
G03X-42372I2500J0D01*
G01X-44872Y751993D02*
G03I0J2500D01*
G01X-24372Y125213D02*
G02I-2500J0D01*
G01X-26872Y127713D02*
G03Y122713I0J-2500D01*
G03Y127713I0J2500D01*
G01X-24372Y125213D02*
G03X-29372I-2500J0D01*
G03X-24372I2500J0D01*
G01X-26872Y127713D02*
G03I0J-2500D01*
G01X-24372Y141213D02*
G02I-2500J0D01*
G01X-26872Y143713D02*
G03Y138713I0J-2500D01*
G03Y143713I0J2500D01*
G01X-24372Y141213D02*
G03X-29372I-2500J0D01*
G03X-24372I2500J0D01*
G01X-26872Y143713D02*
G03I0J-2500D01*
G01X-24372Y232533D02*
G02I-2500J0D01*
G01X-26872Y235033D02*
G03Y230033I0J-2500D01*
G03Y235033I0J2500D01*
G01D02*
G03Y230033I0J-2500D01*
G03Y235033I0J2500D01*
G01X-24372Y232533D02*
G03X-29372I-2500J0D01*
G03X-24372I2500J0D01*
G01X-26872Y235033D02*
G03I0J-2500D01*
G01D02*
G02I0J-2500D01*
G01X-24372Y248533D02*
G02I-2500J0D01*
G01X-26872Y251033D02*
G03Y246033I0J-2500D01*
G03Y251033I0J2500D01*
G01D02*
G03Y246033I0J-2500D01*
G03Y251033I0J2500D01*
G01X-24372Y248533D02*
G03X-29372I-2500J0D01*
G03X-24372I2500J0D01*
G01X-26872Y251033D02*
G03I0J-2500D01*
G01D02*
G02I0J-2500D01*
G01X-24372Y738493D02*
G02I-2500J0D01*
G01X-26872Y735993D02*
G03Y740993I0J2500D01*
G03Y735993I0J-2500D01*
G01X-24372Y738493D02*
G03X-29372I-2500J0D01*
G03X-24372I2500J0D01*
G01X-26872Y735993D02*
G03I0J2500D01*
G01X-24372Y754493D02*
G02I-2500J0D01*
G01X-26872Y751993D02*
G03Y756993I0J2500D01*
G03Y751993I0J-2500D01*
G01X-24372Y754493D02*
G03X-29372I-2500J0D01*
G03X-24372I2500J0D01*
G01X-26872Y751993D02*
G03I0J2500D01*
G01X736866Y821652D02*
X738695Y819832D01*
X738819Y819708D01*
Y679921D01*
G03X746693Y672047I7874J0D01*
G01X779528D01*
G02X787402Y664173I0J-7874D01*
G01Y297835D01*
G02X781496Y291929I-5906J0D01*
G01X780315D01*
G03X774409Y286024I0J-5906D01*
G01Y132480D01*
G03X780315Y126575I5906J1D01*
G01X781496D01*
G02X787402Y120669I0J-5906D01*
G01Y7874D01*
G02X779528Y0I-7874J0D01*
G01X7874D01*
G02X0Y7874I0J7874D01*
G01Y115354D01*
G02X5906Y121260I5906J0D01*
G01X25591D01*
G03X31496Y127165I0J5905D01*
G01Y272835D01*
G03X25591Y278740I-5905J0D01*
G01X5906D01*
G02X0Y284646I0J5906D01*
G01Y664173D01*
G02X7874Y672047I7874J0D01*
G01X40787D01*
G03X48661Y679921I0J7874D01*
G01Y819674D01*
X49201Y820214D01*
X50646Y821652D01*
X327026D01*
X328915Y819773D01*
X328976Y819712D01*
Y792323D01*
G03X336457I3740J0D01*
G01Y819673D01*
X336476Y819692D01*
X338446Y821652D01*
X378606D01*
X380551Y819707D01*
Y741142D01*
G03X406929I13189J0D01*
G01Y819675D01*
X406946Y819692D01*
X408916Y821652D01*
X685296D01*
X686388Y820566D01*
X687244Y819710D01*
Y792323D01*
G03X694724I3740J0D01*
G01Y819670D01*
X694746Y819692D01*
X696716Y821652D01*
X736866D01*
G01X5906Y278740D02*
X25591D01*
G02X31496Y272835I0J-5905D01*
G01Y127165D01*
G02X25591Y121260I-5905J0D01*
G01X5906D01*
G03X0Y115354I0J-5906D01*
G01Y7874D01*
G03X7874Y0I7874J0D01*
G01X779528D01*
G03X787402Y7874I0J7874D01*
G01Y120669D01*
G03X781496Y126575I-5906J0D01*
G01X780315D01*
G02X774409Y132480I0J5906D01*
G01Y286024D01*
G02X780315Y291929I5906J-1D01*
G01X781496D01*
G03X787402Y297835I0J5906D01*
G01Y664173D01*
G03X779528Y672047I-7874J0D01*
G01X746693D01*
G02X738819Y679921I0J7874D01*
G01Y819708D01*
X738695Y819832D01*
X736866Y821652D01*
G01X5906Y278740D02*
G02X0Y284646I0J5906D01*
G01Y664173D01*
G02X7874Y672047I7874J0D01*
G01X40787D01*
G03X48661Y679921I0J7874D01*
G01Y819674D01*
X49201Y820214D01*
X50646Y821652D01*
G01X327026D02*
X50646D01*
G01X106999Y96614D02*
G02X89851I-8574J-10787D01*
G03X91339Y99696I-2449J3083D01*
G01Y105512D01*
G02X105512I7086J0D01*
G01Y99696D01*
G03X106999Y96614I3937J0D01*
G01D02*
G02X89851I-8574J-10787D01*
G03X91339Y99696I-2449J3083D01*
G01Y105512D01*
G02X105512I7086J0D01*
G01Y99696D01*
G03X106999Y96614I3937J0D01*
G01D02*
G02X89851I-8574J-10787D01*
G03X91339Y99696I-2449J3083D01*
G01Y105512D01*
G02X105512I7086J0D01*
G01Y99696D01*
G03X106999Y96614I3937J0D01*
G01D02*
G02X89851I-8574J-10787D01*
G03X91339Y99696I-2449J3083D01*
G01Y105512D01*
G02X105512I7086J0D01*
G01Y99696D01*
G03X106999Y96614I3937J0D01*
G01Y710787D02*
G02X89851I-8574J-10787D01*
G03X91339Y713869I-2449J3083D01*
G01Y719685D01*
G02X105512I7086J0D01*
G01Y713869D01*
G03X106999Y710787I3937J0D01*
G01D02*
G02X89851I-8574J-10787D01*
G03X91339Y713869I-2449J3083D01*
G01Y719685D01*
G02X105512I7086J0D01*
G01Y713869D01*
G03X106999Y710787I3937J0D01*
G01D02*
G02X89851I-8574J-10787D01*
G03X91339Y713869I-2449J3083D01*
G01Y719685D01*
G02X105512I7086J0D01*
G01Y713869D01*
G03X106999Y710787I3937J0D01*
G01D02*
G02X89851I-8574J-10787D01*
G03X91339Y713869I-2449J3083D01*
G01Y719685D01*
G02X105512I7086J0D01*
G01Y713869D01*
G03X106999Y710787I3937J0D01*
G01X327026Y821652D02*
X328915Y819773D01*
X328976Y819712D01*
Y792323D01*
G03X336457I3740J0D01*
G01Y819673D01*
X336476Y819692D01*
X338446Y821652D01*
G01X378606D02*
X338446D01*
G01X378606D02*
X380551Y819707D01*
Y741142D01*
G01X406929D02*
Y819675D01*
X406946Y819692D01*
X408916Y821652D01*
G01X685296D02*
X408916D01*
G01X697857Y96166D02*
G02X680096I-8880J-10536D01*
G03X681496Y99177I-2537J3011D01*
G01Y105315D01*
G02X696457I7481J0D01*
G01Y99177D01*
G03X697857Y96166I3937J0D01*
G01D02*
G02X680096I-8880J-10536D01*
G03X681496Y99177I-2537J3011D01*
G01Y105315D01*
G02X696457I7481J0D01*
G01Y99177D01*
G03X697857Y96166I3937J0D01*
G01D02*
G02X680096I-8880J-10536D01*
G03X681496Y99177I-2537J3011D01*
G01Y105315D01*
G02X696457I7481J0D01*
G01Y99177D01*
G03X697857Y96166I3937J0D01*
G01D02*
G02X680096I-8880J-10536D01*
G03X681496Y99177I-2537J3011D01*
G01Y105315D01*
G02X696457I7481J0D01*
G01Y99177D01*
G03X697857Y96166I3937J0D01*
G01X681496Y713350D02*
Y719488D01*
G02X696457I7481J0D01*
G01Y713350D01*
G03X697857Y710340I3937J0D01*
G02X680096I-8880J-10537D01*
G03X681496Y713350I-2537J3011D01*
G01D02*
Y719488D01*
G02X696457I7481J0D01*
G01Y713350D01*
G03X697857Y710340I3937J0D01*
G02X680096I-8880J-10537D01*
G03X681496Y713350I-2537J3011D01*
G01D02*
Y719488D01*
G02X696457I7481J0D01*
G01Y713350D01*
G03X697857Y710340I3937J0D01*
G02X680096I-8880J-10537D01*
G03X681496Y713350I-2537J3011D01*
G01D02*
Y719488D01*
G02X696457I7481J0D01*
G01Y713350D01*
G03X697857Y710340I3937J0D01*
G02X680096I-8880J-10537D01*
G03X681496Y713350I-2537J3011D01*
G01X696716Y821652D02*
X694746Y819692D01*
X694724Y819670D01*
Y792323D01*
G02X687244I-3740J0D01*
G01Y819710D01*
X686388Y820566D01*
X685296Y821652D01*
G01X736866D02*
X696716D01*
M02*
